(kicad_pcb
	(version 20260206)
	(generator "pcbnew")
	(generator_version "10.0")
	(general
		(thickness 1.6)
		(legacy_teardrops no)
	)
	(paper "A4")
	(title_block
		(title "v1-chassis-manager — T6M_CM_d_v01_1031_1645.brd")
		(comment 1 "Open CloudServer (Microsoft) / footprints 26-35 of 2512")
	)
	(layers
		(0 "F.Cu" signal "TOP")
		(4 "In1.Cu" signal "GND1")
		(6 "In2.Cu" signal "IN1")
		(8 "In3.Cu" signal "VCC1")
		(10 "In4.Cu" signal "VCC2")
		(12 "In5.Cu" signal "GND2")
		(14 "In6.Cu" signal "IN2")
		(16 "In7.Cu" signal "IN3")
		(18 "In8.Cu" signal "GND3")
		(2 "B.Cu" signal "BOTTOM")
		(9 "F.Adhes" user "F.Adhesive")
		(11 "B.Adhes" user "B.Adhesive")
		(13 "F.Paste" user "Package Geometry/Pastemask Top")
		(15 "B.Paste" user "Package Geometry/Pastemask Bottom")
		(5 "F.SilkS" user "Ref Des/Silkscreen Top")
		(7 "B.SilkS" user "Ref Des/Silkscreen Bottom")
		(1 "F.Mask" user "Board Geometry/Soldermask Top")
		(3 "B.Mask" user "Board Geometry/Soldermask Bottom")
		(17 "Dwgs.User" user "User.Drawings")
		(19 "Cmts.User" user "User.Comments")
		(21 "Eco1.User" user "User.Eco1")
		(23 "Eco2.User" user "User.Eco2")
		(25 "Edge.Cuts" user "Board Geometry/Outline")
		(27 "Margin" user)
		(31 "F.CrtYd" user "Package Geometry/Place Bound Top")
		(29 "B.CrtYd" user "Package Geometry/Place Bound Bottom")
		(35 "F.Fab" user "Ref Des/Assembly Top")
		(33 "B.Fab" user "Ref Des/Assembly Bottom")
	)
	(footprint ""
		(layer "F.Cu")
		(at 19.72564 -132.360416)
		(property "Reference" "PR24"
			(at 1.524762 -0.23495 0)
			(unlocked yes)
			(layer "F.SilkS")
			(effects
				(font
					(size 0.7874 0.5842)
					(thickness 0.1524)
				)
				(justify left)
			)
		)
		(property "Value" ""
			(at 0 0 0)
			(layer "F.Fab")
			(effects
				(font
					(size 1.27 1.27)
				)
			)
		)
		(duplicate_pad_numbers_are_jumpers no)
		(fp_line
			(start -0.7874 -0.4064)
			(end 0.7874 -0.4064)
			(stroke
				(width 0.1524)
				(type default)
			)
			(layer "F.SilkS")
		)
		(fp_line
			(start -0.7874 0.4064)
			(end -0.7874 -0.4064)
			(stroke
				(width 0.1524)
				(type default)
			)
			(layer "F.SilkS")
		)
		(fp_line
			(start 0.7874 -0.4064)
			(end 0.7874 0.4064)
			(stroke
				(width 0.1524)
				(type default)
			)
			(layer "F.SilkS")
		)
		(fp_line
			(start 0.7874 0.4064)
			(end -0.7874 0.4064)
			(stroke
				(width 0.1524)
				(type default)
			)
			(layer "F.SilkS")
		)
		(fp_poly
			(pts
				(xy -0.508 0.2794) (xy -0.508 0.2286) (xy -0.635 0.2286) (xy -0.635 -0.254) (xy -0.5334 -0.254)
				(xy -0.5334 -0.2794) (xy 0.5334 -0.2794) (xy 0.5334 -0.254) (xy 0.635 -0.254) (xy 0.635 0.254) (xy 0.5334 0.254)
				(xy 0.5334 0.2794)
			)
			(stroke
				(width 0)
				(type default)
			)
			(fill no)
			(layer "F.CrtYd")
		)
		(pad "1" smd rect
			(at 0.40005 0)
			(size 0.4572 0.508)
			(layers "F.Cu" "F.Mask" "F.Paste")
			(net "P3V3_NODE1")
		)
		(pad "2" smd rect
			(at -0.40005 0)
			(size 0.4572 0.508)
			(layers "F.Cu" "F.Mask" "F.Paste")
			(net "PWRGD_NODE1_P1V05_PG")
		)
	)
	(footprint ""
		(layer "F.Cu")
		(at 56.725312 -148.290788 180)
		(property "Reference" "R315"
			(at 1.708912 1.13792 0)
			(unlocked yes)
			(layer "F.SilkS")
			(effects
				(font
					(size 0.7874 0.5842)
					(thickness 0.1524)
				)
			)
		)
		(property "Value" ""
			(at 0 0 180)
			(layer "F.Fab")
			(effects
				(font
					(size 1.27 1.27)
				)
			)
		)
		(duplicate_pad_numbers_are_jumpers no)
		(fp_line
			(start 1.2954 0.5842)
			(end -1.2954 0.5842)
			(stroke
				(width 0.1524)
				(type default)
			)
			(layer "F.SilkS")
		)
		(fp_line
			(start 1.2954 -0.5842)
			(end 1.2954 0.5842)
			(stroke
				(width 0.1524)
				(type default)
			)
			(layer "F.SilkS")
		)
		(fp_line
			(start -1.2954 0.5842)
			(end -1.2954 -0.5842)
			(stroke
				(width 0.1524)
				(type default)
			)
			(layer "F.SilkS")
		)
		(fp_line
			(start -1.2954 -0.5842)
			(end 1.2954 -0.5842)
			(stroke
				(width 0.1524)
				(type default)
			)
			(layer "F.SilkS")
		)
		(fp_poly
			(pts
				(xy 1.143 -0.3556) (xy 1.143 0.3556) (xy 0.8636 0.3556) (xy 0.8636 0.4572) (xy -0.8636 0.4572) (xy -0.8636 0.4318)
				(xy -0.8636 0.3556) (xy -1.143 0.3556) (xy -1.143 -0.3556) (xy -0.8636 -0.3556) (xy -0.8636 -0.4572)
				(xy 0.8636 -0.4572) (xy 0.8636 -0.3556)
			)
			(stroke
				(width 0)
				(type default)
			)
			(fill no)
			(layer "F.CrtYd")
		)
		(pad "1" smd rect
			(at 0.7366 0 270)
			(size 0.7112 0.8128)
			(layers "F.Cu" "F.Mask" "F.Paste")
			(net "GND")
		)
		(pad "2" smd rect
			(at -0.7366 0 270)
			(size 0.7112 0.8128)
			(layers "F.Cu" "F.Mask" "F.Paste")
			(net "BMC_NODE1_DACRSET")
		)
	)
	(footprint ""
		(layer "F.Cu")
		(at 123.93676 -185.205624 -90)
		(property "Reference" "R860"
			(at -4.768088 -0.152908 90)
			(unlocked yes)
			(layer "F.SilkS")
			(effects
				(font
					(size 0.7874 0.5842)
					(thickness 0.1524)
				)
				(justify left)
			)
		)
		(property "Value" ""
			(at 0 0 270)
			(layer "F.Fab")
			(effects
				(font
					(size 1.27 1.27)
				)
			)
		)
		(duplicate_pad_numbers_are_jumpers no)
		(fp_line
			(start -0.7874 0.4064)
			(end -0.7874 -0.4064)
			(stroke
				(width 0.1524)
				(type default)
			)
			(layer "F.SilkS")
		)
		(fp_line
			(start 0.7874 0.4064)
			(end -0.7874 0.4064)
			(stroke
				(width 0.1524)
				(type default)
			)
			(layer "F.SilkS")
		)
		(fp_line
			(start -0.7874 -0.4064)
			(end 0.7874 -0.4064)
			(stroke
				(width 0.1524)
				(type default)
			)
			(layer "F.SilkS")
		)
		(fp_line
			(start 0.7874 -0.4064)
			(end 0.7874 0.4064)
			(stroke
				(width 0.1524)
				(type default)
			)
			(layer "F.SilkS")
		)
		(fp_poly
			(pts
				(xy -0.508 0.2794) (xy -0.508 0.2286) (xy -0.635 0.2286) (xy -0.635 -0.254) (xy -0.5334 -0.254)
				(xy -0.5334 -0.2794) (xy 0.5334 -0.2794) (xy 0.5334 -0.254) (xy 0.635 -0.254) (xy 0.635 0.254) (xy 0.5334 0.254)
				(xy 0.5334 0.2794)
			)
			(stroke
				(width 0)
				(type default)
			)
			(fill no)
			(layer "F.CrtYd")
		)
		(pad "1" smd rect
			(at 0.40005 0 270)
			(size 0.4572 0.508)
			(layers "F.Cu" "F.Mask" "F.Paste")
			(net "T8_NODE1_EN")
		)
		(pad "2" smd rect
			(at -0.40005 0 270)
			(size 0.4572 0.508)
			(layers "F.Cu" "F.Mask" "F.Paste")
			(net "T8_NODE1_EN_R")
		)
	)
	(footprint ""
		(layer "F.Cu")
		(at 66.491358 -8.501888 180)
		(property "Reference" "PC53"
			(at 1.450086 4.286504 0)
			(unlocked yes)
			(layer "F.SilkS")
			(effects
				(font
					(size 0.7874 0.5842)
					(thickness 0.1524)
				)
				(justify left)
			)
		)
		(property "Value" ""
			(at 0 0 180)
			(layer "F.Fab")
			(effects
				(font
					(size 1.27 1.27)
				)
			)
		)
		(duplicate_pad_numbers_are_jumpers no)
		(fp_line
			(start 0.7874 0.4064)
			(end -0.7874 0.4064)
			(stroke
				(width 0.1524)
				(type default)
			)
			(layer "F.SilkS")
		)
		(fp_line
			(start 0.7874 -0.4064)
			(end 0.7874 0.4064)
			(stroke
				(width 0.1524)
				(type default)
			)
			(layer "F.SilkS")
		)
		(fp_line
			(start 0 0.381)
			(end 0 -0.381)
			(stroke
				(width 0.1524)
				(type default)
			)
			(layer "F.SilkS")
		)
		(fp_line
			(start -0.7874 0.4064)
			(end -0.7874 -0.4064)
			(stroke
				(width 0.1524)
				(type default)
			)
			(layer "F.SilkS")
		)
		(fp_line
			(start -0.7874 -0.4064)
			(end 0.7874 -0.4064)
			(stroke
				(width 0.1524)
				(type default)
			)
			(layer "F.SilkS")
		)
		(fp_poly
			(pts
				(xy -0.5334 0.254) (xy -0.635 0.254) (xy -0.635 0.2286) (xy -0.635 -0.254) (xy -0.5334 -0.254) (xy -0.5334 -0.2794)
				(xy 0.5334 -0.2794) (xy 0.5334 -0.254) (xy 0.635 -0.254) (xy 0.635 0.254) (xy 0.5334 0.254) (xy 0.5334 0.2794)
				(xy -0.508 0.2794) (xy -0.5334 0.2794)
			)
			(stroke
				(width 0)
				(type default)
			)
			(fill no)
			(layer "F.CrtYd")
		)
		(pad "1" smd rect
			(at 0.40005 0 180)
			(size 0.4572 0.508)
			(layers "F.Cu" "F.Mask" "F.Paste")
			(net "P3V3_NODE1_FB")
		)
		(pad "2" smd rect
			(at -0.40005 0 180)
			(size 0.4572 0.508)
			(layers "F.Cu" "F.Mask" "F.Paste")
			(net "P3V3_NODE1")
		)
	)
	(footprint ""
		(layer "F.Cu")
		(at 79.558388 -96.661732 90)
		(property "Reference" "R1052"
			(at 3.264408 -0.421894 90)
			(unlocked yes)
			(layer "F.SilkS")
			(effects
				(font
					(size 0.7874 0.5842)
					(thickness 0.1524)
				)
				(justify left)
			)
		)
		(property "Value" ""
			(at 0 0 90)
			(layer "F.Fab")
			(effects
				(font
					(size 1.27 1.27)
				)
			)
		)
		(duplicate_pad_numbers_are_jumpers no)
		(fp_line
			(start 0.7874 -0.4064)
			(end 0.7874 0.4064)
			(stroke
				(width 0.1524)
				(type default)
			)
			(layer "F.SilkS")
		)
		(fp_line
			(start -0.7874 -0.4064)
			(end 0.7874 -0.4064)
			(stroke
				(width 0.1524)
				(type default)
			)
			(layer "F.SilkS")
		)
		(fp_line
			(start 0.7874 0.4064)
			(end -0.7874 0.4064)
			(stroke
				(width 0.1524)
				(type default)
			)
			(layer "F.SilkS")
		)
		(fp_line
			(start -0.7874 0.4064)
			(end -0.7874 -0.4064)
			(stroke
				(width 0.1524)
				(type default)
			)
			(layer "F.SilkS")
		)
		(fp_poly
			(pts
				(xy -0.508 0.2794) (xy -0.508 0.2286) (xy -0.635 0.2286) (xy -0.635 -0.254) (xy -0.5334 -0.254)
				(xy -0.5334 -0.2794) (xy 0.5334 -0.2794) (xy 0.5334 -0.254) (xy 0.635 -0.254) (xy 0.635 0.254) (xy 0.5334 0.254)
				(xy 0.5334 0.2794)
			)
			(stroke
				(width 0)
				(type default)
			)
			(fill no)
			(layer "F.CrtYd")
		)
		(pad "1" smd rect
			(at 0.40005 0 90)
			(size 0.4572 0.508)
			(layers "F.Cu" "F.Mask" "F.Paste")
			(net "CLK_33K_CPU_NODE1_SUSCLK_R")
		)
		(pad "2" smd rect
			(at -0.40005 0 90)
			(size 0.4572 0.508)
			(layers "F.Cu" "F.Mask" "F.Paste")
			(net "CLK_33K_CPU_NODE1_SUSCLK")
		)
	)
	(footprint ""
		(layer "F.Cu")
		(at 48.262286 -114.424714 180)
		(property "Reference" "PC11"
			(at 1.882394 2.665476 0)
			(unlocked yes)
			(layer "F.SilkS")
			(effects
				(font
					(size 0.7874 0.5842)
					(thickness 0.1524)
				)
				(justify left)
			)
		)
		(property "Value" ""
			(at 0 0 180)
			(layer "F.Fab")
			(effects
				(font
					(size 1.27 1.27)
				)
			)
		)
		(duplicate_pad_numbers_are_jumpers no)
		(fp_line
			(start 2.2098 0.9398)
			(end -2.2098 0.9398)
			(stroke
				(width 0.1524)
				(type default)
			)
			(layer "F.SilkS")
		)
		(fp_line
			(start 2.2098 -0.9398)
			(end 2.2098 0.9398)
			(stroke
				(width 0.1524)
				(type default)
			)
			(layer "F.SilkS")
		)
		(fp_line
			(start 0 -0.9398)
			(end 0 0.9398)
			(stroke
				(width 0.1524)
				(type default)
			)
			(layer "F.SilkS")
		)
		(fp_line
			(start -2.2098 0.9398)
			(end -2.2098 -0.9398)
			(stroke
				(width 0.1524)
				(type default)
			)
			(layer "F.SilkS")
		)
		(fp_line
			(start -2.2098 -0.9398)
			(end 2.2098 -0.9398)
			(stroke
				(width 0.1524)
				(type default)
			)
			(layer "F.SilkS")
		)
		(fp_poly
			(pts
				(xy -1.6764 0.889) (xy -1.6764 0.7874) (xy -2.0574 0.7874) (xy -2.0574 -0.7874) (xy -1.6764 -0.7874)
				(xy -1.6764 -0.9398) (xy 1.6764 -0.9398) (xy 1.6764 -0.7874) (xy 2.0574 -0.7874) (xy 2.0574 0.7874)
				(xy 1.6764 0.7874) (xy 1.6764 0.9398) (xy -1.6764 0.9398)
			)
			(stroke
				(width 0)
				(type default)
			)
			(fill no)
			(layer "F.CrtYd")
		)
		(fp_line
			(start 1.700022 0.899922)
			(end -1.700022 0.899922)
			(stroke
				(width 0.1)
				(type default)
			)
			(layer "F.Fab")
		)
		(fp_line
			(start 1.700022 -0.899922)
			(end 1.700022 0.899922)
			(stroke
				(width 0.1)
				(type default)
			)
			(layer "F.Fab")
		)
		(fp_line
			(start -1.700022 0.899922)
			(end -1.700022 -0.899922)
			(stroke
				(width 0.1)
				(type default)
			)
			(layer "F.Fab")
		)
		(fp_line
			(start -1.700022 -0.899922)
			(end 1.700022 -0.899922)
			(stroke
				(width 0.1)
				(type default)
			)
			(layer "F.Fab")
		)
		(pad "1" smd rect
			(at 1.4732 0 180)
			(size 1.1684 1.5748)
			(layers "F.Cu" "F.Mask" "F.Paste")
			(net "P12V_AUX")
		)
		(pad "2" smd rect
			(at -1.4732 0 180)
			(size 1.1684 1.5748)
			(layers "F.Cu" "F.Mask" "F.Paste")
			(net "GND")
		)
	)
	(footprint ""
		(layer "F.Cu")
		(at -73.134728 -265.390884)
		(property "Reference" "H10_SRW"
			(at 1.819148 -1.728978 0)
			(unlocked yes)
			(layer "B.SilkS")
			(effects
				(font
					(size 0.7874 0.5842)
					(thickness 0.1524)
				)
				(justify left mirror)
			)
		)
		(property "Value" ""
			(at 0 0 0)
			(layer "F.Fab")
			(effects
				(font
					(size 1.27 1.27)
				)
			)
		)
		(duplicate_pad_numbers_are_jumpers no)
		(fp_poly
			(pts
				(arc
					(start 0.3302 0)
					(mid -0.3302 0)
					(end 0.3302 0)
				)
			)
			(stroke
				(width 0)
				(type default)
			)
			(fill no)
			(layer "B.CrtYd")
		)
		(pad "1" thru_hole circle
			(at 0 0)
			(size 0.508 0.508)
			(drill 0.254)
			(layers "*.Cu" "*.Mask")
			(remove_unused_layers no)
			(net "Net_219")
			(clearance 0.127)
			(thermal_gap 0.127)
			(padstack
				(mode front_inner_back)
				(layer "Inner"
					(shape circle)
					(size 0.508 0.508)
					(clearance 0.127)
				)
				(layer "B.Cu"
					(shape circle)
					(size 0.6604 0.6604)
					(clearance 0.0508)
				)
			)
		)
	)
	(footprint ""
		(layer "F.Cu")
		(at 152.579578 -69.060822)
		(property "Reference" "R505"
			(at -1.658366 -2.39395 0)
			(unlocked yes)
			(layer "F.SilkS")
			(effects
				(font
					(size 0.7874 0.5842)
					(thickness 0.1524)
				)
				(justify left)
			)
		)
		(property "Value" ""
			(at 0 0 0)
			(layer "F.Fab")
			(effects
				(font
					(size 1.27 1.27)
				)
			)
		)
		(duplicate_pad_numbers_are_jumpers no)
		(fp_line
			(start -0.7874 -0.4064)
			(end 0.7874 -0.4064)
			(stroke
				(width 0.1524)
				(type default)
			)
			(layer "F.SilkS")
		)
		(fp_line
			(start -0.7874 0.4064)
			(end -0.7874 -0.4064)
			(stroke
				(width 0.1524)
				(type default)
			)
			(layer "F.SilkS")
		)
		(fp_line
			(start 0.7874 -0.4064)
			(end 0.7874 0.4064)
			(stroke
				(width 0.1524)
				(type default)
			)
			(layer "F.SilkS")
		)
		(fp_line
			(start 0.7874 0.4064)
			(end -0.7874 0.4064)
			(stroke
				(width 0.1524)
				(type default)
			)
			(layer "F.SilkS")
		)
		(fp_poly
			(pts
				(xy -0.508 0.2794) (xy -0.508 0.2286) (xy -0.635 0.2286) (xy -0.635 -0.254) (xy -0.5334 -0.254)
				(xy -0.5334 -0.2794) (xy 0.5334 -0.2794) (xy 0.5334 -0.254) (xy 0.635 -0.254) (xy 0.635 0.254) (xy 0.5334 0.254)
				(xy 0.5334 0.2794)
			)
			(stroke
				(width 0)
				(type default)
			)
			(fill no)
			(layer "F.CrtYd")
		)
		(pad "1" smd rect
			(at 0.40005 0)
			(size 0.4572 0.508)
			(layers "F.Cu" "F.Mask" "F.Paste")
			(net "GND")
		)
		(pad "2" smd rect
			(at -0.40005 0)
			(size 0.4572 0.508)
			(layers "F.Cu" "F.Mask" "F.Paste")
			(net "SATA_NODE1_XTLOUT")
		)
	)
	(footprint ""
		(layer "F.Cu")
		(at 95.813372 -161.137092)
		(property "Reference" "U105"
			(at 88.933274 71.779892 90)
			(unlocked yes)
			(layer "F.SilkS")
			(effects
				(font
					(size 0.7874 0.5842)
					(thickness 0.1524)
				)
			)
		)
		(property "Value" ""
			(at 0 0 0)
			(layer "F.Fab")
			(effects
				(font
					(size 1.27 1.27)
				)
			)
		)
		(duplicate_pad_numbers_are_jumpers no)
		(fp_line
			(start -1.651 -1.905)
			(end 1.651 -1.905)
			(stroke
				(width 0.1524)
				(type default)
			)
			(layer "F.SilkS")
		)
		(fp_line
			(start -1.651 1.905)
			(end -1.651 -1.905)
			(stroke
				(width 0.1524)
				(type default)
			)
			(layer "F.SilkS")
		)
		(fp_line
			(start 1.651 -1.905)
			(end 1.651 1.905)
			(stroke
				(width 0.1524)
				(type default)
			)
			(layer "F.SilkS")
		)
		(fp_line
			(start 1.651 1.905)
			(end -1.651 1.905)
			(stroke
				(width 0.1524)
				(type default)
			)
			(layer "F.SilkS")
		)
		(fp_poly
			(pts
				(xy -1.524 0.7112) (xy -1.524 1.7526) (xy -0.508 1.7526) (xy -0.508 0.6985) (xy 0.508 0.6985) (xy 0.508 1.7526)
				(xy 1.524 1.7526) (xy 1.524 0.6985) (xy 1.524 -0.6985) (xy 0.508 -0.6985) (xy 0.508 -1.7526) (xy -0.508 -1.7526)
				(xy -0.508 -0.6985) (xy -1.524 -0.6985) (xy -1.524 0.6985)
			)
			(stroke
				(width 0)
				(type default)
			)
			(fill no)
			(layer "F.CrtYd")
		)
		(fp_text user "G"
			(at -1.856994 1.673352 0)
			(unlocked yes)
			(layer "F.SilkS")
			(effects
				(font
					(size 0.635 0.4064)
					(thickness 0.1524)
				)
			)
		)
		(fp_text user "D"
			(at 0.511556 -2.534412 0)
			(unlocked yes)
			(layer "F.SilkS")
			(effects
				(font
					(size 0.635 0.4064)
					(thickness 0.1524)
				)
			)
		)
		(fp_text user "S"
			(at 2.015998 0.473964 0)
			(unlocked yes)
			(layer "F.SilkS")
			(effects
				(font
					(size 0.635 0.4064)
					(thickness 0.1524)
				)
			)
		)
		(pad "D" smd rect
			(at 0 -1.1176)
			(size 1.016 1.27)
			(layers "F.Cu" "F.Mask" "F.Paste")
			(net "N52411040")
		)
		(pad "G" smd rect
			(at -1.016 1.1176)
			(size 1.016 1.27)
			(layers "F.Cu" "F.Mask" "F.Paste")
			(net "N52410998")
		)
		(pad "S" smd rect
			(at 1.016 1.1176)
			(size 1.016 1.27)
			(layers "F.Cu" "F.Mask" "F.Paste")
			(net "GND")
		)
	)
	(footprint ""
		(layer "F.Cu")
		(at 68.353686 -121.044462 -90)
		(property "Reference" "R255"
			(at 6.142736 -6.807708 90)
			(unlocked yes)
			(layer "F.SilkS")
			(effects
				(font
					(size 0.7874 0.5842)
					(thickness 0.1524)
				)
				(justify left)
			)
		)
		(property "Value" ""
			(at 0 0 270)
			(layer "F.Fab")
			(effects
				(font
					(size 1.27 1.27)
				)
			)
		)
		(duplicate_pad_numbers_are_jumpers no)
		(fp_line
			(start -0.7874 0.4064)
			(end -0.7874 -0.4064)
			(stroke
				(width 0.1524)
				(type default)
			)
			(layer "F.SilkS")
		)
		(fp_line
			(start 0.7874 0.4064)
			(end -0.7874 0.4064)
			(stroke
				(width 0.1524)
				(type default)
			)
			(layer "F.SilkS")
		)
		(fp_line
			(start -0.7874 -0.4064)
			(end 0.7874 -0.4064)
			(stroke
				(width 0.1524)
				(type default)
			)
			(layer "F.SilkS")
		)
		(fp_line
			(start 0.7874 -0.4064)
			(end 0.7874 0.4064)
			(stroke
				(width 0.1524)
				(type default)
			)
			(layer "F.SilkS")
		)
		(fp_poly
			(pts
				(xy -0.508 0.2794) (xy -0.508 0.2286) (xy -0.635 0.2286) (xy -0.635 -0.254) (xy -0.5334 -0.254)
				(xy -0.5334 -0.2794) (xy 0.5334 -0.2794) (xy 0.5334 -0.254) (xy 0.635 -0.254) (xy 0.635 0.254) (xy 0.5334 0.254)
				(xy 0.5334 0.2794)
			)
			(stroke
				(width 0)
				(type default)
			)
			(fill no)
			(layer "F.CrtYd")
		)
		(pad "1" smd rect
			(at 0.40005 0 270)
			(size 0.4572 0.508)
			(layers "F.Cu" "F.Mask" "F.Paste")
			(net "IRQ_LVC3_CPU_NODE1_WAKE_L")
		)
		(pad "2" smd rect
			(at -0.40005 0 270)
			(size 0.4572 0.508)
			(layers "F.Cu" "F.Mask" "F.Paste")
			(net "IRQ_LVC3_CPU_NODE1_WAKE_R_L")
		)
	)
)
